FILE_TYPE = MACRO_DRAWING;
SET COLOR_WIRE YELLOW;
SET COLOR_PROP ORANGE;
SET COLOR_DOT WHITE;
SET COLOR_ARC YELLOW;
SET COLOR_BODY GREEN;
SET COLOR_NOTE PURPLE;
SET PROP_DISPLAY VALUE;
SET PAGE_NUMBER P109;
FORCEADD QUANTA_TITLE_BLOCK_C..1
(-1325 3300);
FORCEPROP 1 LAST CUSTOM_TXT_CDS <NAME_2>
J 0
(-4500 3350);
FORCEPROP 1 LAST CUSTOM_TXT_CDS <NAME_1>
J 0
(-4500 3475);
FORCEPROP 1 LAST CUSTOM_TXT_CDS <Q_NUMBER>
J 0
(-2728 3403);
DISPLAY 1.212766 (-2728 3403);
FORCEPROP 1 LAST CUSTOM_TXT_CDS <Q_PROJ>
J 0
(-3707 3402);
DISPLAY 1.212766 (-3707 3402);
FORCEPROP 1 LAST CUSTOM_TXT_CDS <Q_REV>
J 0
(-1509 3403);
DISPLAY 1.212766 (-1509 3403);
FORCEPROP 1 LAST CUSTOM_TXT_CDS <CON_LAST_MODIFIED>
J 0
(-3210 3315);
DISPLAY 0.978723 (-3210 3315);
FORCEPROP 1 LAST CUSTOM_TXT_CDS <CON_PAGE_NUM> OF <CON_TOTAL_PAGES>
J 0
(-1771 3318);
DISPLAY 0.978723 (-1771 3318);
FORCEPROP 1 LAST Q_TITLE Blank
J 0
(-10600 3400);
DISPLAY 2.446809 (-10600 3400);
PAINT GREEN (-10600 3400);
FORCEPROP 2 LAST CDS_LIB pure_quanta
J 0
(-1325 3300);
DISPLAY INVISIBLE (-1325 3300);
FORCEPROP 1 LAST CDS_LMAN_SYM_OUTLINE -9475,6775,100,-125
J 0
(-1325 3300);
DISPLAY 0.468085 (-1325 3300);
PAINT GREEN (-1325 3300);
DISPLAY INVISIBLE (-1325 3300);
FORCEPROP 2 LAST PAGE_BORDER TRUE
J 0
(-9215 8550);
DISPLAY 0.638298 (-9215 8550);
PAINT PINK (-9215 8550);
DISPLAY INVISIBLE (-9215 8550);
FORCEPROP 2 LAST CDS_XR_PAGE_TITLE CR-110 : @T6G_MB_LIB.T6G(SCH_1):PAGE110
J 0
(-9215 8550);
DISPLAY 0.638298 (-9215 8550);
PAINT PINK (-9215 8550);
DISPLAY INVISIBLE (-9215 8550);
FORCEPROP 2 LAST CUSTOM_TXT_CDS <XR_PAGE_TITLE>
J 0
(-9215 8550);
DISPLAY 0.638298 (-9215 8550);
PAINT PINK (-9215 8550);
DISPLAY INVISIBLE (-9215 8550);
FORCEPROP 1 LAST COMMENT_BODY TRUE
J 0
(-1313 3287);
DISPLAY 0.978723 (-1313 3287);
PAINT GREEN (-1313 3287);
DISPLAY INVISIBLE (-1313 3287);
FORCEPROP 1 LAST Q_DEPT BU9
J 1
(-5088 3349);
DISPLAY 1.957447 (-5088 3349);
PAINT GREEN (-5088 3349);
DISPLAY INVISIBLE (-5088 3349);
FORCEPROP 0 LAST CDS_CON_LAST_MODIFIED Thu Aug 24 10:14:17 2023
J 0
(-3210 3315);
DISPLAY INVISIBLE (-3210 3315);
QUIT
